(kicad_pcb
	(version 20260206)
	(generator "pcbnew")
	(generator_version "10.0")
	(general
		(thickness 1.6)
		(legacy_teardrops no)
	)
	(paper "A4")
	(title_block
		(title "03242023_DA0F0TMBIJ0_F0T_Motherboard_J_brd_V01_OCP.brd")
		(comment 1 "Grand Teton / footprints 3412-3418 of 6105")
	)
	(layers
		(0 "F.Cu" signal "TOP")
		(4 "In1.Cu" signal "GND")
		(6 "In2.Cu" signal "IN1")
		(8 "In3.Cu" signal "GND1")
		(10 "In4.Cu" signal "IN2")
		(12 "In5.Cu" signal "GND2")
		(14 "In6.Cu" signal "IN3")
		(16 "In7.Cu" signal "GND3")
		(18 "In8.Cu" signal "VCC")
		(20 "In9.Cu" signal "VCC1")
		(22 "In10.Cu" signal "GND4")
		(24 "In11.Cu" signal "IN4")
		(26 "In12.Cu" signal "GND5")
		(28 "In13.Cu" signal "IN5")
		(30 "In14.Cu" signal "GND6")
		(32 "In15.Cu" signal "IN6")
		(34 "In16.Cu" signal "GND7")
		(2 "B.Cu" signal "BOTTOM")
		(9 "F.Adhes" user "F.Adhesive")
		(11 "B.Adhes" user "B.Adhesive")
		(13 "F.Paste" user "Package Geometry/Pastemask Top")
		(15 "B.Paste" user "Package Geometry/Pastemask Bottom")
		(5 "F.SilkS" user "Ref Des/Silkscreen Top")
		(7 "B.SilkS" user "Ref Des/Silkscreen Bottom")
		(1 "F.Mask" user "Board Geometry/Soldermask Top")
		(3 "B.Mask" user "Board Geometry/Soldermask Bottom")
		(17 "Dwgs.User" user "User.Drawings")
		(19 "Cmts.User" user "User.Comments")
		(21 "Eco1.User" user "User.Eco1")
		(23 "Eco2.User" user "User.Eco2")
		(25 "Edge.Cuts" user "Board Geometry/Outline")
		(27 "Margin" user)
		(31 "F.CrtYd" user "Package Geometry/Place Bound Top")
		(29 "B.CrtYd" user "Package Geometry/Place Bound Bottom")
		(35 "F.Fab" user "Ref Des/Assembly Top")
		(33 "B.Fab" user "Ref Des/Assembly Bottom")
	)
	(footprint ""
		(layer "F.Cu")
		(at 355.2444 -386.425948 180)
		(property "Reference" "R4569"
			(at 0 0 180)
			(layer "F.SilkS")
			(hide yes)
			(effects
				(font
					(size 1.27 1.27)
				)
			)
		)
		(property "Value" ""
			(at 0 0 180)
			(layer "F.Fab")
			(effects
				(font
					(size 1.27 1.27)
				)
			)
		)
		(duplicate_pad_numbers_are_jumpers no)
		(fp_line
			(start 0.7874 0.4064)
			(end -0.7874 0.4064)
			(stroke
				(width 0.1524)
				(type default)
			)
			(layer "F.SilkS")
		)
		(fp_line
			(start 0.7874 -0.4064)
			(end 0.7874 0.4064)
			(stroke
				(width 0.1524)
				(type default)
			)
			(layer "F.SilkS")
		)
		(fp_line
			(start -0.7874 0.4064)
			(end -0.7874 -0.4064)
			(stroke
				(width 0.1524)
				(type default)
			)
			(layer "F.SilkS")
		)
		(fp_line
			(start -0.7874 -0.4064)
			(end 0.7874 -0.4064)
			(stroke
				(width 0.1524)
				(type default)
			)
			(layer "F.SilkS")
		)
		(fp_line
			(start 0.67945 0.3048)
			(end 0.120396 0.3048)
			(stroke
				(width 0.1)
				(type default)
			)
			(layer "F.Fab")
		)
		(fp_line
			(start 0.67945 -0.3048)
			(end 0.67945 0.3048)
			(stroke
				(width 0.1)
				(type default)
			)
			(layer "F.Fab")
		)
		(fp_line
			(start 0.12065 -0.2794)
			(end 0.12065 -0.3048)
			(stroke
				(width 0.1)
				(type default)
			)
			(layer "F.Fab")
		)
		(fp_line
			(start 0.12065 -0.3048)
			(end 0.67945 -0.3048)
			(stroke
				(width 0.1)
				(type default)
			)
			(layer "F.Fab")
		)
		(fp_line
			(start 0.120396 0.3048)
			(end 0.120396 0.2794)
			(stroke
				(width 0.1)
				(type default)
			)
			(layer "F.Fab")
		)
		(fp_line
			(start 0.120396 0.2794)
			(end -0.12065 0.2794)
			(stroke
				(width 0.1)
				(type default)
			)
			(layer "F.Fab")
		)
		(fp_line
			(start -0.12065 0.3048)
			(end -0.67945 0.3048)
			(stroke
				(width 0.1)
				(type default)
			)
			(layer "F.Fab")
		)
		(fp_line
			(start -0.12065 0.2794)
			(end -0.12065 0.3048)
			(stroke
				(width 0.1)
				(type default)
			)
			(layer "F.Fab")
		)
		(fp_line
			(start -0.12065 -0.2794)
			(end 0.12065 -0.2794)
			(stroke
				(width 0.1)
				(type default)
			)
			(layer "F.Fab")
		)
		(fp_line
			(start -0.12065 -0.305054)
			(end -0.12065 -0.2794)
			(stroke
				(width 0.1)
				(type default)
			)
			(layer "F.Fab")
		)
		(fp_line
			(start -0.67945 0.3048)
			(end -0.67945 -0.305054)
			(stroke
				(width 0.1)
				(type default)
			)
			(layer "F.Fab")
		)
		(fp_line
			(start -0.67945 -0.305054)
			(end -0.12065 -0.305054)
			(stroke
				(width 0.1)
				(type default)
			)
			(layer "F.Fab")
		)
		(pad "1" smd circle
			(at -0.40005 0 180)
			(size 0 0)
			(layers "F.Cu" "F.Mask" "F.Paste")
			(net "GPU_3V3IO_RSVD1")
		)
		(pad "2" smd circle
			(at 0.40005 0 180)
			(size 0 0)
			(layers "F.Cu" "F.Mask" "F.Paste")
			(net "GPU_3V3IO_RSVD1_ISO")
		)
	)
	(footprint ""
		(layer "F.Cu")
		(at 418.485828 -174.396654)
		(property "Reference" "PC187"
			(at 0 0 0)
			(layer "F.SilkS")
			(hide yes)
			(effects
				(font
					(size 1.27 1.27)
				)
			)
		)
		(property "Value" ""
			(at 0 0 0)
			(layer "F.Fab")
			(effects
				(font
					(size 1.27 1.27)
				)
			)
		)
		(duplicate_pad_numbers_are_jumpers no)
		(fp_line
			(start -0.7874 -0.4064)
			(end 0.7874 -0.4064)
			(stroke
				(width 0.1524)
				(type default)
			)
			(layer "F.SilkS")
		)
		(fp_line
			(start -0.7874 0.4064)
			(end -0.7874 -0.4064)
			(stroke
				(width 0.1524)
				(type default)
			)
			(layer "F.SilkS")
		)
		(fp_line
			(start 0.7874 -0.4064)
			(end 0.7874 0.4064)
			(stroke
				(width 0.1524)
				(type default)
			)
			(layer "F.SilkS")
		)
		(fp_line
			(start 0.7874 0.4064)
			(end -0.7874 0.4064)
			(stroke
				(width 0.1524)
				(type default)
			)
			(layer "F.SilkS")
		)
		(fp_line
			(start -0.67945 -0.305054)
			(end -0.12065 -0.305054)
			(stroke
				(width 0.1)
				(type default)
			)
			(layer "F.Fab")
		)
		(fp_line
			(start -0.67945 0.3048)
			(end -0.67945 -0.305054)
			(stroke
				(width 0.1)
				(type default)
			)
			(layer "F.Fab")
		)
		(fp_line
			(start -0.12065 -0.305054)
			(end -0.12065 -0.2794)
			(stroke
				(width 0.1)
				(type default)
			)
			(layer "F.Fab")
		)
		(fp_line
			(start -0.12065 -0.2794)
			(end 0.12065 -0.2794)
			(stroke
				(width 0.1)
				(type default)
			)
			(layer "F.Fab")
		)
		(fp_line
			(start -0.12065 0.2794)
			(end -0.12065 0.3048)
			(stroke
				(width 0.1)
				(type default)
			)
			(layer "F.Fab")
		)
		(fp_line
			(start -0.12065 0.3048)
			(end -0.67945 0.3048)
			(stroke
				(width 0.1)
				(type default)
			)
			(layer "F.Fab")
		)
		(fp_line
			(start 0.120396 0.2794)
			(end -0.12065 0.2794)
			(stroke
				(width 0.1)
				(type default)
			)
			(layer "F.Fab")
		)
		(fp_line
			(start 0.120396 0.3048)
			(end 0.120396 0.2794)
			(stroke
				(width 0.1)
				(type default)
			)
			(layer "F.Fab")
		)
		(fp_line
			(start 0.12065 -0.3048)
			(end 0.67945 -0.3048)
			(stroke
				(width 0.1)
				(type default)
			)
			(layer "F.Fab")
		)
		(fp_line
			(start 0.12065 -0.2794)
			(end 0.12065 -0.3048)
			(stroke
				(width 0.1)
				(type default)
			)
			(layer "F.Fab")
		)
		(fp_line
			(start 0.67945 -0.3048)
			(end 0.67945 0.3048)
			(stroke
				(width 0.1)
				(type default)
			)
			(layer "F.Fab")
		)
		(fp_line
			(start 0.67945 0.3048)
			(end 0.120396 0.3048)
			(stroke
				(width 0.1)
				(type default)
			)
			(layer "F.Fab")
		)
		(pad "1" smd circle
			(at -0.40005 0)
			(size 0 0)
			(layers "F.Cu" "F.Mask" "F.Paste")
			(net "PVCCINFAON_CPU0_VDD1")
		)
		(pad "2" smd circle
			(at 0.40005 0)
			(size 0 0)
			(layers "F.Cu" "F.Mask" "F.Paste")
			(net "GND")
		)
	)
	(footprint ""
		(layer "F.Cu")
		(at 254.35433 -54.844442 -90)
		(property "Reference" "R3948"
			(at 0 0 270)
			(layer "F.SilkS")
			(hide yes)
			(effects
				(font
					(size 1.27 1.27)
				)
			)
		)
		(property "Value" ""
			(at 0 0 270)
			(layer "F.Fab")
			(effects
				(font
					(size 1.27 1.27)
				)
			)
		)
		(duplicate_pad_numbers_are_jumpers no)
		(fp_line
			(start -0.7874 0.4064)
			(end -0.7874 -0.4064)
			(stroke
				(width 0.1524)
				(type default)
			)
			(layer "F.SilkS")
		)
		(fp_line
			(start 0.7874 0.4064)
			(end -0.7874 0.4064)
			(stroke
				(width 0.1524)
				(type default)
			)
			(layer "F.SilkS")
		)
		(fp_line
			(start -0.7874 -0.4064)
			(end 0.7874 -0.4064)
			(stroke
				(width 0.1524)
				(type default)
			)
			(layer "F.SilkS")
		)
		(fp_line
			(start 0.7874 -0.4064)
			(end 0.7874 0.4064)
			(stroke
				(width 0.1524)
				(type default)
			)
			(layer "F.SilkS")
		)
		(fp_line
			(start -0.67945 0.3048)
			(end -0.67945 -0.305054)
			(stroke
				(width 0.1)
				(type default)
			)
			(layer "F.Fab")
		)
		(fp_line
			(start -0.12065 0.3048)
			(end -0.67945 0.3048)
			(stroke
				(width 0.1)
				(type default)
			)
			(layer "F.Fab")
		)
		(fp_line
			(start 0.120396 0.3048)
			(end 0.120396 0.2794)
			(stroke
				(width 0.1)
				(type default)
			)
			(layer "F.Fab")
		)
		(fp_line
			(start 0.67945 0.3048)
			(end 0.120396 0.3048)
			(stroke
				(width 0.1)
				(type default)
			)
			(layer "F.Fab")
		)
		(fp_line
			(start -0.12065 0.2794)
			(end -0.12065 0.3048)
			(stroke
				(width 0.1)
				(type default)
			)
			(layer "F.Fab")
		)
		(fp_line
			(start 0.120396 0.2794)
			(end -0.12065 0.2794)
			(stroke
				(width 0.1)
				(type default)
			)
			(layer "F.Fab")
		)
		(fp_line
			(start -0.12065 -0.2794)
			(end 0.12065 -0.2794)
			(stroke
				(width 0.1)
				(type default)
			)
			(layer "F.Fab")
		)
		(fp_line
			(start 0.12065 -0.2794)
			(end 0.12065 -0.3048)
			(stroke
				(width 0.1)
				(type default)
			)
			(layer "F.Fab")
		)
		(fp_line
			(start 0.12065 -0.3048)
			(end 0.67945 -0.3048)
			(stroke
				(width 0.1)
				(type default)
			)
			(layer "F.Fab")
		)
		(fp_line
			(start 0.67945 -0.3048)
			(end 0.67945 0.3048)
			(stroke
				(width 0.1)
				(type default)
			)
			(layer "F.Fab")
		)
		(fp_line
			(start -0.67945 -0.305054)
			(end -0.12065 -0.305054)
			(stroke
				(width 0.1)
				(type default)
			)
			(layer "F.Fab")
		)
		(fp_line
			(start -0.12065 -0.305054)
			(end -0.12065 -0.2794)
			(stroke
				(width 0.1)
				(type default)
			)
			(layer "F.Fab")
		)
		(pad "1" smd circle
			(at -0.40005 0 270)
			(size 0 0)
			(layers "F.Cu" "F.Mask" "F.Paste")
			(net "P3V3_AUX")
		)
		(pad "2" smd circle
			(at 0.40005 0 270)
			(size 0 0)
			(layers "F.Cu" "F.Mask" "F.Paste")
			(net "HP_LVC3_E1S_0_HSC_PWRGD")
		)
	)
	(footprint ""
		(layer "F.Cu")
		(at 171.867322 -28.03779 90)
		(property "Reference" "PR4009"
			(at 0 0 90)
			(layer "F.SilkS")
			(hide yes)
			(effects
				(font
					(size 1.27 1.27)
				)
			)
		)
		(property "Value" ""
			(at 0 0 90)
			(layer "F.Fab")
			(effects
				(font
					(size 1.27 1.27)
				)
			)
		)
		(duplicate_pad_numbers_are_jumpers no)
		(fp_line
			(start 0.7874 -0.4064)
			(end 0.7874 0.4064)
			(stroke
				(width 0.1524)
				(type default)
			)
			(layer "F.SilkS")
		)
		(fp_line
			(start -0.7874 -0.4064)
			(end 0.7874 -0.4064)
			(stroke
				(width 0.1524)
				(type default)
			)
			(layer "F.SilkS")
		)
		(fp_line
			(start 0.7874 0.4064)
			(end -0.7874 0.4064)
			(stroke
				(width 0.1524)
				(type default)
			)
			(layer "F.SilkS")
		)
		(fp_line
			(start -0.7874 0.4064)
			(end -0.7874 -0.4064)
			(stroke
				(width 0.1524)
				(type default)
			)
			(layer "F.SilkS")
		)
		(fp_line
			(start -0.12065 -0.305054)
			(end -0.12065 -0.2794)
			(stroke
				(width 0.1)
				(type default)
			)
			(layer "F.Fab")
		)
		(fp_line
			(start -0.67945 -0.305054)
			(end -0.12065 -0.305054)
			(stroke
				(width 0.1)
				(type default)
			)
			(layer "F.Fab")
		)
		(fp_line
			(start 0.67945 -0.3048)
			(end 0.67945 0.3048)
			(stroke
				(width 0.1)
				(type default)
			)
			(layer "F.Fab")
		)
		(fp_line
			(start 0.12065 -0.3048)
			(end 0.67945 -0.3048)
			(stroke
				(width 0.1)
				(type default)
			)
			(layer "F.Fab")
		)
		(fp_line
			(start 0.12065 -0.2794)
			(end 0.12065 -0.3048)
			(stroke
				(width 0.1)
				(type default)
			)
			(layer "F.Fab")
		)
		(fp_line
			(start -0.12065 -0.2794)
			(end 0.12065 -0.2794)
			(stroke
				(width 0.1)
				(type default)
			)
			(layer "F.Fab")
		)
		(fp_line
			(start 0.120396 0.2794)
			(end -0.12065 0.2794)
			(stroke
				(width 0.1)
				(type default)
			)
			(layer "F.Fab")
		)
		(fp_line
			(start -0.12065 0.2794)
			(end -0.12065 0.3048)
			(stroke
				(width 0.1)
				(type default)
			)
			(layer "F.Fab")
		)
		(fp_line
			(start 0.67945 0.3048)
			(end 0.120396 0.3048)
			(stroke
				(width 0.1)
				(type default)
			)
			(layer "F.Fab")
		)
		(fp_line
			(start 0.120396 0.3048)
			(end 0.120396 0.2794)
			(stroke
				(width 0.1)
				(type default)
			)
			(layer "F.Fab")
		)
		(fp_line
			(start -0.12065 0.3048)
			(end -0.67945 0.3048)
			(stroke
				(width 0.1)
				(type default)
			)
			(layer "F.Fab")
		)
		(fp_line
			(start -0.67945 0.3048)
			(end -0.67945 -0.305054)
			(stroke
				(width 0.1)
				(type default)
			)
			(layer "F.Fab")
		)
		(pad "1" smd circle
			(at -0.40005 0 90)
			(size 0 0)
			(layers "F.Cu" "F.Mask" "F.Paste")
			(net "P12V_SCM_R")
		)
		(pad "2" smd circle
			(at 0.40005 0 90)
			(size 0 0)
			(layers "F.Cu" "F.Mask" "F.Paste")
			(net "P12V_SCM_OV_FB")
		)
	)
	(footprint ""
		(layer "F.Cu")
		(at 62.28588 -16.220948 -90)
		(property "Reference" "R3170"
			(at 0 0 270)
			(layer "F.SilkS")
			(hide yes)
			(effects
				(font
					(size 1.27 1.27)
				)
			)
		)
		(property "Value" ""
			(at 0 0 270)
			(layer "F.Fab")
			(effects
				(font
					(size 1.27 1.27)
				)
			)
		)
		(duplicate_pad_numbers_are_jumpers no)
		(fp_line
			(start -0.7874 0.4064)
			(end -0.7874 -0.4064)
			(stroke
				(width 0.1524)
				(type default)
			)
			(layer "F.SilkS")
		)
		(fp_line
			(start 0.7874 0.4064)
			(end -0.7874 0.4064)
			(stroke
				(width 0.1524)
				(type default)
			)
			(layer "F.SilkS")
		)
		(fp_line
			(start -0.7874 -0.4064)
			(end 0.7874 -0.4064)
			(stroke
				(width 0.1524)
				(type default)
			)
			(layer "F.SilkS")
		)
		(fp_line
			(start 0.7874 -0.4064)
			(end 0.7874 0.4064)
			(stroke
				(width 0.1524)
				(type default)
			)
			(layer "F.SilkS")
		)
		(fp_line
			(start -0.67945 0.3048)
			(end -0.67945 -0.305054)
			(stroke
				(width 0.1)
				(type default)
			)
			(layer "F.Fab")
		)
		(fp_line
			(start -0.12065 0.3048)
			(end -0.67945 0.3048)
			(stroke
				(width 0.1)
				(type default)
			)
			(layer "F.Fab")
		)
		(fp_line
			(start 0.120396 0.3048)
			(end 0.120396 0.2794)
			(stroke
				(width 0.1)
				(type default)
			)
			(layer "F.Fab")
		)
		(fp_line
			(start 0.67945 0.3048)
			(end 0.120396 0.3048)
			(stroke
				(width 0.1)
				(type default)
			)
			(layer "F.Fab")
		)
		(fp_line
			(start -0.12065 0.2794)
			(end -0.12065 0.3048)
			(stroke
				(width 0.1)
				(type default)
			)
			(layer "F.Fab")
		)
		(fp_line
			(start 0.120396 0.2794)
			(end -0.12065 0.2794)
			(stroke
				(width 0.1)
				(type default)
			)
			(layer "F.Fab")
		)
		(fp_line
			(start -0.12065 -0.2794)
			(end 0.12065 -0.2794)
			(stroke
				(width 0.1)
				(type default)
			)
			(layer "F.Fab")
		)
		(fp_line
			(start 0.12065 -0.2794)
			(end 0.12065 -0.3048)
			(stroke
				(width 0.1)
				(type default)
			)
			(layer "F.Fab")
		)
		(fp_line
			(start 0.12065 -0.3048)
			(end 0.67945 -0.3048)
			(stroke
				(width 0.1)
				(type default)
			)
			(layer "F.Fab")
		)
		(fp_line
			(start 0.67945 -0.3048)
			(end 0.67945 0.3048)
			(stroke
				(width 0.1)
				(type default)
			)
			(layer "F.Fab")
		)
		(fp_line
			(start -0.67945 -0.305054)
			(end -0.12065 -0.305054)
			(stroke
				(width 0.1)
				(type default)
			)
			(layer "F.Fab")
		)
		(fp_line
			(start -0.12065 -0.305054)
			(end -0.12065 -0.2794)
			(stroke
				(width 0.1)
				(type default)
			)
			(layer "F.Fab")
		)
		(pad "1" smd circle
			(at -0.40005 0 270)
			(size 0 0)
			(layers "F.Cu" "F.Mask" "F.Paste")
			(net "OCP_V3_2_ISO_BIF1_EN")
		)
		(pad "2" smd circle
			(at 0.40005 0 270)
			(size 0 0)
			(layers "F.Cu" "F.Mask" "F.Paste")
			(net "OCP_V3_2_BIF1_R_N")
		)
	)
	(footprint ""
		(layer "F.Cu")
		(at 214.75827 -72.641714 90)
		(property "Reference" "R1294"
			(at 0 0 90)
			(layer "F.SilkS")
			(hide yes)
			(effects
				(font
					(size 1.27 1.27)
				)
			)
		)
		(property "Value" ""
			(at 0 0 90)
			(layer "F.Fab")
			(effects
				(font
					(size 1.27 1.27)
				)
			)
		)
		(duplicate_pad_numbers_are_jumpers no)
		(fp_line
			(start 0.7874 -0.4064)
			(end 0.7874 0.4064)
			(stroke
				(width 0.1524)
				(type default)
			)
			(layer "F.SilkS")
		)
		(fp_line
			(start -0.7874 -0.4064)
			(end 0.7874 -0.4064)
			(stroke
				(width 0.1524)
				(type default)
			)
			(layer "F.SilkS")
		)
		(fp_line
			(start 0.7874 0.4064)
			(end -0.7874 0.4064)
			(stroke
				(width 0.1524)
				(type default)
			)
			(layer "F.SilkS")
		)
		(fp_line
			(start -0.7874 0.4064)
			(end -0.7874 -0.4064)
			(stroke
				(width 0.1524)
				(type default)
			)
			(layer "F.SilkS")
		)
		(fp_line
			(start -0.12065 -0.305054)
			(end -0.12065 -0.2794)
			(stroke
				(width 0.1)
				(type default)
			)
			(layer "F.Fab")
		)
		(fp_line
			(start -0.67945 -0.305054)
			(end -0.12065 -0.305054)
			(stroke
				(width 0.1)
				(type default)
			)
			(layer "F.Fab")
		)
		(fp_line
			(start 0.67945 -0.3048)
			(end 0.67945 0.3048)
			(stroke
				(width 0.1)
				(type default)
			)
			(layer "F.Fab")
		)
		(fp_line
			(start 0.12065 -0.3048)
			(end 0.67945 -0.3048)
			(stroke
				(width 0.1)
				(type default)
			)
			(layer "F.Fab")
		)
		(fp_line
			(start 0.12065 -0.2794)
			(end 0.12065 -0.3048)
			(stroke
				(width 0.1)
				(type default)
			)
			(layer "F.Fab")
		)
		(fp_line
			(start -0.12065 -0.2794)
			(end 0.12065 -0.2794)
			(stroke
				(width 0.1)
				(type default)
			)
			(layer "F.Fab")
		)
		(fp_line
			(start 0.120396 0.2794)
			(end -0.12065 0.2794)
			(stroke
				(width 0.1)
				(type default)
			)
			(layer "F.Fab")
		)
		(fp_line
			(start -0.12065 0.2794)
			(end -0.12065 0.3048)
			(stroke
				(width 0.1)
				(type default)
			)
			(layer "F.Fab")
		)
		(fp_line
			(start 0.67945 0.3048)
			(end 0.120396 0.3048)
			(stroke
				(width 0.1)
				(type default)
			)
			(layer "F.Fab")
		)
		(fp_line
			(start 0.120396 0.3048)
			(end 0.120396 0.2794)
			(stroke
				(width 0.1)
				(type default)
			)
			(layer "F.Fab")
		)
		(fp_line
			(start -0.12065 0.3048)
			(end -0.67945 0.3048)
			(stroke
				(width 0.1)
				(type default)
			)
			(layer "F.Fab")
		)
		(fp_line
			(start -0.67945 0.3048)
			(end -0.67945 -0.305054)
			(stroke
				(width 0.1)
				(type default)
			)
			(layer "F.Fab")
		)
		(pad "1" smd circle
			(at -0.40005 0 90)
			(size 0 0)
			(layers "F.Cu" "F.Mask" "F.Paste")
			(net "NCSI_BMC_TX_EN_R")
		)
		(pad "2" smd circle
			(at 0.40005 0 90)
			(size 0 0)
			(layers "F.Cu" "F.Mask" "F.Paste")
			(net "RMII_BMC_OCP_TX_EN")
		)
	)
	(footprint ""
		(layer "F.Cu")
		(at 340.713568 -402.371052 -90)
		(property "Reference" "C1554"
			(at 0 0 270)
			(layer "F.SilkS")
			(hide yes)
			(effects
				(font
					(size 1.27 1.27)
				)
			)
		)
		(property "Value" ""
			(at 0 0 270)
			(layer "F.Fab")
			(effects
				(font
					(size 1.27 1.27)
				)
			)
		)
		(duplicate_pad_numbers_are_jumpers no)
		(fp_line
			(start -0.299974 0.150114)
			(end -0.299974 -0.150114)
			(stroke
				(width 0.1)
				(type default)
			)
			(layer "F.Fab")
		)
		(fp_line
			(start 0.299974 0.150114)
			(end -0.299974 0.150114)
			(stroke
				(width 0.1)
				(type default)
			)
			(layer "F.Fab")
		)
		(fp_line
			(start -0.299974 -0.150114)
			(end 0.299974 -0.150114)
			(stroke
				(width 0.1)
				(type default)
			)
			(layer "F.Fab")
		)
		(fp_line
			(start 0.299974 -0.150114)
			(end 0.299974 0.150114)
			(stroke
				(width 0.1)
				(type default)
			)
			(layer "F.Fab")
		)
		(pad "1" smd rect
			(at -0.2667 0 270)
			(size 0.3048 0.381)
			(layers "F.Cu" "F.Mask" "F.Paste")
			(net "P5E_CPU0_PE4_TX_C_DN<12>")
		)
		(pad "2" smd rect
			(at 0.2667 0 270)
			(size 0.3048 0.381)
			(layers "F.Cu" "F.Mask" "F.Paste")
			(net "P5E_CPU0_PE4_TX_DN<12>")
		)
	)
)
